FILE_TYPE = MACRO_DRAWING;
SET COLOR_WIRE YELLOW;
SET COLOR_PROP ORANGE;
SET COLOR_DOT WHITE;
SET COLOR_ARC YELLOW;
SET COLOR_BODY GREEN;
SET COLOR_NOTE PURPLE;
SET PROP_DISPLAY VALUE;
SET PAGE_NUMBER P34;
FORCEADD OFFPAGE..2
(-600 5925);
FORCEPROP 2 LAST $XR1 80 
J 0
(-321 5925);
DISPLAY 0.638298 (-321 5925);
PAINT MONO (-321 5925);
FORCEPROP 2 LAST $XR0 34 
J 0
(-411 5925);
DISPLAY 0.638298 (-411 5925);
PAINT MONO (-411 5925);
FORCEPROP 2 LAST CDS_LIB standard
J 0
(-600 5925);
DISPLAY INVISIBLE (-600 5925);
FORCEPROP 1 LAST OFFPAGE TRUE
J 0
(-275 5800);
DISPLAY 0.872340 (-275 5800);
PAINT GREEN (-275 5800);
DISPLAY INVISIBLE (-275 5800);
FORCEPROP 1 LAST COMMENT_BODY TRUE
J 0
(-645 5830);
DISPLAY 0.872340 (-645 5830);
PAINT GREEN (-645 5830);
DISPLAY INVISIBLE (-645 5830);
FORCEPROP 2 LAST PATH I1
J 0
(-300 5975);
DISPLAY 0.680851 (-300 5975);
DISPLAY INVISIBLE (-300 5975);
FORCEADD OFFPAGE..2
(-525 4925);
FORCEPROP 2 LAST $XR1 34 
J 0
(-246 4925);
DISPLAY 0.638298 (-246 4925);
PAINT MONO (-246 4925);
FORCEPROP 2 LAST $XR0 28 
J 0
(-336 4925);
DISPLAY 0.638298 (-336 4925);
PAINT MONO (-336 4925);
FORCEPROP 2 LAST CDS_LIB standard
J 0
(-525 4925);
DISPLAY INVISIBLE (-525 4925);
FORCEPROP 1 LAST OFFPAGE TRUE
J 0
(-200 4800);
DISPLAY 0.872340 (-200 4800);
PAINT GREEN (-200 4800);
DISPLAY INVISIBLE (-200 4800);
FORCEPROP 1 LAST COMMENT_BODY TRUE
J 0
(-570 4830);
DISPLAY 0.872340 (-570 4830);
PAINT GREEN (-570 4830);
DISPLAY INVISIBLE (-570 4830);
FORCEPROP 2 LAST PATH I104
J 0
(-225 4975);
DISPLAY 0.680851 (-225 4975);
DISPLAY INVISIBLE (-225 4975);
FORCEADD OFFPAGE..2
(-525 4850);
FORCEPROP 2 LAST $XR1 34 
J 0
(-246 4850);
DISPLAY 0.638298 (-246 4850);
PAINT MONO (-246 4850);
FORCEPROP 2 LAST $XR0 28 
J 0
(-336 4850);
DISPLAY 0.638298 (-336 4850);
PAINT MONO (-336 4850);
FORCEPROP 2 LAST CDS_LIB standard
J 0
(-525 4850);
DISPLAY INVISIBLE (-525 4850);
FORCEPROP 1 LAST OFFPAGE TRUE
J 0
(-200 4725);
DISPLAY 0.872340 (-200 4725);
PAINT GREEN (-200 4725);
DISPLAY INVISIBLE (-200 4725);
FORCEPROP 1 LAST COMMENT_BODY TRUE
J 0
(-570 4755);
DISPLAY 0.872340 (-570 4755);
PAINT GREEN (-570 4755);
DISPLAY INVISIBLE (-570 4755);
FORCEPROP 2 LAST PATH I105
J 0
(-225 4900);
DISPLAY 0.680851 (-225 4900);
DISPLAY INVISIBLE (-225 4900);
FORCEADD Q_RES..1
(-1625 4925);
FORCEPROP 1 LAST LOCATION R495
J 0
(-1975 4925);
DISPLAY 0.489362 (-1975 4925);
PAINT SKYBLUE (-1975 4925);
FORCEPROP 2 LAST $SEC 1
J 0
(-1675 5125);
DISPLAY 0.680851 (-1675 5125);
PAINT MONO (-1675 5125);
DISPLAY INVISIBLE (-1675 5125);
FORCEPROP 2 LAST CDS_SEC 1
J 0
(-1675 5125);
DISPLAY 0.680851 (-1675 5125);
DISPLAY INVISIBLE (-1675 5125);
FORCEPROP 1 LASTPIN (-1725 4925) $PN 1
J 0
(-1713 4937);
DISPLAY 0.489362 (-1713 4937);
PAINT MONO (-1713 4937);
FORCEPROP 1 LASTPIN (-1525 4925) $PN 2
J 0
(-1563 4937);
DISPLAY 0.489362 (-1563 4937);
PAINT MONO (-1563 4937);
FORCEPROP 1 LAST VALUE 4.7K
J 0
(-1500 4925);
DISPLAY 0.489362 (-1500 4925);
PAINT SKYBLUE (-1500 4925);
FORCEPROP 1 LAST MATERIAL CHIP
J 0
(-1850 4925);
DISPLAY 0.489362 (-1850 4925);
PAINT SKYBLUE (-1850 4925);
FORCEPROP 1 LAST PACK_TYPE 0402LF
J 0
(-1375 4775);
DISPLAY 0.510638 (-1375 4775);
PAINT SKYBLUE (-1375 4775);
DISPLAY INVISIBLE (-1375 4775);
FORCEPROP 1 LAST TOLERANCE 5%
J 0
(-1500 4925);
DISPLAY 0.510638 (-1500 4925);
PAINT SKYBLUE (-1500 4925);
DISPLAY INVISIBLE (-1500 4925);
FORCEPROP 1 LAST WATTAGE 1/16W
J 2
(-1650 4775);
DISPLAY 0.510638 (-1650 4775);
PAINT SKYBLUE (-1650 4775);
DISPLAY INVISIBLE (-1650 4775);
FORCEPROP 2 LAST CDS_LIB pure_quanta
J 0
(-1625 4925);
DISPLAY INVISIBLE (-1625 4925);
FORCEPROP 1 LAST PATH I106
J 0
(-1675 5075);
DISPLAY 0.978723 (-1675 5075);
PAINT WHITE (-1675 5075);
DISPLAY INVISIBLE (-1675 5075);
FORCEPROP 1 LAST PART_NUMBER CS24702JB10
J 0
(-1675 5025);
DISPLAY 0.510638 (-1675 5025);
PAINT SKYBLUE (-1675 5025);
DISPLAY INVISIBLE (-1675 5025);
FORCEADD Q_RES..1
(-1625 4850);
FORCEPROP 1 LAST LOCATION R498
J 0
(-1975 4850);
DISPLAY 0.489362 (-1975 4850);
PAINT SKYBLUE (-1975 4850);
FORCEPROP 2 LAST $SEC 1
J 0
(-1675 5050);
DISPLAY 0.680851 (-1675 5050);
PAINT MONO (-1675 5050);
DISPLAY INVISIBLE (-1675 5050);
FORCEPROP 2 LAST CDS_SEC 1
J 0
(-1675 5050);
DISPLAY 0.680851 (-1675 5050);
DISPLAY INVISIBLE (-1675 5050);
FORCEPROP 1 LASTPIN (-1725 4850) $PN 1
J 0
(-1713 4862);
DISPLAY 0.489362 (-1713 4862);
PAINT MONO (-1713 4862);
FORCEPROP 1 LASTPIN (-1525 4850) $PN 2
J 0
(-1563 4862);
DISPLAY 0.489362 (-1563 4862);
PAINT MONO (-1563 4862);
FORCEPROP 1 LAST VALUE 2.2K
J 0
(-1500 4850);
DISPLAY 0.489362 (-1500 4850);
PAINT SKYBLUE (-1500 4850);
FORCEPROP 1 LAST MATERIAL CHIP
J 0
(-1850 4850);
DISPLAY 0.489362 (-1850 4850);
PAINT SKYBLUE (-1850 4850);
FORCEPROP 1 LAST PACK_TYPE 0402LF
J 0
(-1375 4700);
DISPLAY 0.510638 (-1375 4700);
PAINT SKYBLUE (-1375 4700);
DISPLAY INVISIBLE (-1375 4700);
FORCEPROP 1 LAST TOLERANCE 5%
J 0
(-1500 4850);
DISPLAY 0.510638 (-1500 4850);
PAINT SKYBLUE (-1500 4850);
DISPLAY INVISIBLE (-1500 4850);
FORCEPROP 1 LAST WATTAGE 1/16W
J 2
(-1650 4700);
DISPLAY 0.510638 (-1650 4700);
PAINT SKYBLUE (-1650 4700);
DISPLAY INVISIBLE (-1650 4700);
FORCEPROP 2 LAST CDS_LIB pure_quanta
J 0
(-1625 4850);
DISPLAY INVISIBLE (-1625 4850);
FORCEPROP 1 LAST PATH I107
J 0
(-1675 5000);
DISPLAY 0.978723 (-1675 5000);
PAINT WHITE (-1675 5000);
DISPLAY INVISIBLE (-1675 5000);
FORCEPROP 1 LAST PART_NUMBER CS22202JB07
J 0
(-1675 4950);
DISPLAY 0.510638 (-1675 4950);
PAINT SKYBLUE (-1675 4950);
DISPLAY INVISIBLE (-1675 4950);
FORCEADD UNIVERSAL_POWER..1
R 2
(-2025 5400);
FORCEPROP 3 LASTPIN (-2025 5350) SIG_NAME PVDD18_S5_P0\g
J 0
(-2015 5360);
DISPLAY 0.659574 (-2015 5360);
PAINT MONO (-2015 5360);
DISPLAY INVISIBLE (-2015 5360);
FORCEPROP 1 LAST HDL_POWER PVDD18_S5_P0
J 1
(-2025 5450);
DISPLAY 0.489362 (-2025 5450);
PAINT GREEN (-2025 5450);
FORCEPROP 2 LAST CDS_LIB pure_quanta_power
J 0
(-2025 5400);
DISPLAY INVISIBLE (-2025 5400);
FORCEPROP 1 LAST PATH I108
J 2
(-2075 5425);
DISPLAY 0.872340 (-2075 5425);
PAINT AQUA (-2075 5425);
DISPLAY INVISIBLE (-2075 5425);
FORCEADD UNIVERSAL_GND..1
(-4600 2250);
FORCEPROP 3 LASTPIN (-4600 2300) SIG_NAME GND\g
J 0
(-4590 2310);
DISPLAY 0.659574 (-4590 2310);
PAINT MONO (-4590 2310);
DISPLAY INVISIBLE (-4590 2310);
FORCEPROP 2 LAST CDS_LIB pure_quanta_power
J 0
(-4600 2250);
DISPLAY INVISIBLE (-4600 2250);
FORCEPROP 1 LAST HDL_POWER GND
J 1
(-4575 2175);
DISPLAY 0.872340 (-4575 2175);
PAINT GREEN (-4575 2175);
DISPLAY INVISIBLE (-4575 2175);
FORCEPROP 1 LAST PATH I123
J 0
(-4525 2250);
DISPLAY 0.872340 (-4525 2250);
PAINT AQUA (-4525 2250);
DISPLAY INVISIBLE (-4525 2250);
FORCEADD Q_CAP..1
(-4600 2450);
FORCEPROP 1 LAST LOCATION C5000
J 0
(-4550 2550);
DISPLAY 0.638298 (-4550 2550);
FORCEPROP 0 LAST $SEC 1
J 0
(-4550 2600);
DISPLAY 0.680851 (-4550 2600);
PAINT MONO (-4550 2600);
DISPLAY INVISIBLE (-4550 2600);
FORCEPROP 0 LAST CDS_SEC 1
J 0
(-4550 2600);
DISPLAY 0.680851 (-4550 2600);
DISPLAY INVISIBLE (-4550 2600);
FORCEPROP 1 LASTPIN (-4600 2550) $PN 1
J 0
(-4590 2530);
DISPLAY 0.787234 (-4590 2530);
PAINT MONO (-4590 2530);
FORCEPROP 1 LASTPIN (-4600 2350) $PN 2
J 0
(-4590 2330);
DISPLAY 0.787234 (-4590 2330);
PAINT MONO (-4590 2330);
FORCEPROP 1 LAST MATERIAL X7R
J 0
(-4550 2350);
DISPLAY 0.638298 (-4550 2350);
FORCEPROP 1 LAST VOLTAGE 50V
J 0
(-4550 2450);
DISPLAY 0.638298 (-4550 2450);
FORCEPROP 1 LAST TOLERANCE 5%
J 0
(-4550 2400);
DISPLAY 0.638298 (-4550 2400);
FORCEPROP 1 LAST VALUE 1000PF
J 0
(-4550 2500);
DISPLAY 0.638298 (-4550 2500);
FORCEPROP 1 LAST PACK_TYPE 0402
J 0
(-4550 2250);
DISPLAY 0.638298 (-4550 2250);
FORCEPROP 2 LAST CDS_LIB pure_quanta
J 0
(-4600 2450);
DISPLAY INVISIBLE (-4600 2450);
FORCEPROP 1 LAST PATH I124
J 0
(-4550 2600);
DISPLAY 0.978723 (-4550 2600);
PAINT WHITE (-4550 2600);
DISPLAY INVISIBLE (-4550 2600);
FORCEPROP 1 LAST PART_NUMBER TMP_QCH21006JB10
J 0
(-4550 2300);
DISPLAY 0.638298 (-4550 2300);
DISPLAY INVISIBLE (-4550 2300);
FORCEADD Q_RES..1
(-5025 2725);
FORCEPROP 1 LAST LOCATION R6100
J 0
(-4900 2725);
DISPLAY 0.489362 (-4900 2725);
PAINT SKYBLUE (-4900 2725);
FORCEPROP 0 LAST $SEC 1
J 0
(-4900 2750);
DISPLAY 0.680851 (-4900 2750);
PAINT MONO (-4900 2750);
DISPLAY INVISIBLE (-4900 2750);
FORCEPROP 0 LAST CDS_SEC 1
J 0
(-4900 2750);
DISPLAY 0.680851 (-4900 2750);
DISPLAY INVISIBLE (-4900 2750);
FORCEPROP 1 LASTPIN (-5125 2725) $PN 1
J 0
(-5113 2737);
DISPLAY 0.489362 (-5113 2737);
PAINT MONO (-5113 2737);
FORCEPROP 1 LASTPIN (-4925 2725) $PN 2
J 0
(-4963 2737);
DISPLAY 0.489362 (-4963 2737);
PAINT MONO (-4963 2737);
FORCEPROP 1 LAST VALUE 49.9
J 2
(-5125 2725);
DISPLAY 0.489362 (-5125 2725);
PAINT SKYBLUE (-5125 2725);
FORCEPROP 2 LAST CDS_LIB pure_quanta
J 0
(-5025 2725);
DISPLAY INVISIBLE (-5025 2725);
FORCEPROP 1 LAST WATTAGE 1/16W
J 2
(-4625 2650);
DISPLAY 0.489362 (-4625 2650);
PAINT SKYBLUE (-4625 2650);
DISPLAY INVISIBLE (-4625 2650);
FORCEPROP 1 LAST MATERIAL CHIP
J 0
(-4600 2650);
DISPLAY 0.489362 (-4600 2650);
PAINT SKYBLUE (-4600 2650);
DISPLAY INVISIBLE (-4600 2650);
FORCEPROP 1 LAST PACK_TYPE 0402LF
J 0
(-4975 2650);
DISPLAY 0.489362 (-4975 2650);
PAINT SKYBLUE (-4975 2650);
DISPLAY INVISIBLE (-4975 2650);
FORCEPROP 1 LAST TOLERANCE 1%
J 0
(-5050 2650);
DISPLAY 0.489362 (-5050 2650);
PAINT SKYBLUE (-5050 2650);
DISPLAY INVISIBLE (-5050 2650);
FORCEPROP 1 LAST PATH I125
J 0
(-5075 2875);
DISPLAY 0.978723 (-5075 2875);
PAINT WHITE (-5075 2875);
DISPLAY INVISIBLE (-5075 2875);
FORCEPROP 1 LAST PART_NUMBER CS04992FB07
J 0
(-5000 2775);
DISPLAY 0.489362 (-5000 2775);
PAINT SKYBLUE (-5000 2775);
DISPLAY INVISIBLE (-5000 2775);
FORCEADD PCA9617ADP..1
(-7200 5575);
FORCEPROP 1 LAST LOCATION U27
J 0
(-7474 5985);
DISPLAY 0.489362 (-7474 5985);
PAINT SKYBLUE (-7474 5985);
FORCEPROP 0 LAST $SEC 1
J 0
(-7425 6125);
DISPLAY 0.680851 (-7425 6125);
PAINT MONO (-7425 6125);
DISPLAY INVISIBLE (-7425 6125);
FORCEPROP 0 LAST CDS_SEC 1
J 0
(-7425 6125);
DISPLAY 1.021277 (-7425 6125);
DISPLAY INVISIBLE (-7425 6125);
FORCEPROP 0 LASTPIN (-6775 5375) $PN 5
J 0
(-6765 5385);
DISPLAY 0.489362 (-6765 5385);
PAINT MONO (-6765 5385);
FORCEPROP 0 LASTPIN (-7625 5375) $PN 4
J 2
(-7635 5385);
DISPLAY 0.489362 (-7635 5385);
PAINT MONO (-7635 5385);
FORCEPROP 0 LASTPIN (-7625 5625) $PN 2
J 2
(-7635 5635);
DISPLAY 0.489362 (-7635 5635);
PAINT MONO (-7635 5635);
FORCEPROP 0 LASTPIN (-6775 5625) $PN 7
J 0
(-6765 5635);
DISPLAY 0.489362 (-6765 5635);
PAINT MONO (-6765 5635);
FORCEPROP 0 LASTPIN (-7625 5525) $PN 3
J 2
(-7635 5535);
DISPLAY 0.489362 (-7635 5535);
PAINT MONO (-7635 5535);
FORCEPROP 0 LASTPIN (-6775 5525) $PN 6
J 0
(-6765 5535);
DISPLAY 0.489362 (-6765 5535);
PAINT MONO (-6765 5535);
FORCEPROP 0 LASTPIN (-7625 5775) $PN 1
J 2
(-7635 5785);
DISPLAY 0.489362 (-7635 5785);
PAINT MONO (-7635 5785);
FORCEPROP 0 LASTPIN (-6775 5775) $PN 8
J 0
(-6765 5785);
DISPLAY 0.489362 (-6765 5785);
PAINT MONO (-6765 5785);
FORCEPROP 2 LAST PART_TYPE SMLF
J 0
(-7425 6075);
DISPLAY 1.021277 (-7425 6075);
FORCEPROP 1 LAST MATERIAL IC
J 0
(-7474 5880);
DISPLAY 0.489362 (-7474 5880);
PAINT SKYBLUE (-7474 5880);
FORCEPROP 2 LAST VALUE PCA9617ADP
J 0
(-7425 6025);
DISPLAY 0.489362 (-7425 6025);
PAINT SKYBLUE (-7425 6025);
FORCEPROP 1 LAST NEEDS_NO_SIZE TRUE
J 0
(-6925 5275);
DISPLAY 0.468085 (-6925 5275);
PAINT GREEN (-6925 5275);
DISPLAY INVISIBLE (-6925 5275);
FORCEPROP 1 LAST CDS_LMAN_SYM_OUTLINE -275,300,275,-300
J 0
(-7200 5575);
DISPLAY 0.468085 (-7200 5575);
PAINT GREEN (-7200 5575);
DISPLAY INVISIBLE (-7200 5575);
FORCEPROP 2 LAST CDS_LIB pure_quanta
J 0
(-7200 5575);
DISPLAY INVISIBLE (-7200 5575);
FORCEPROP 1 LAST PATH I18
J 0
(-7200 5575);
DISPLAY 0.723404 (-7200 5575);
PAINT GREEN (-7200 5575);
DISPLAY INVISIBLE (-7200 5575);
FORCEPROP 1 LAST PART_NUMBER AL009617K02
J 0
(-7474 5935);
DISPLAY 0.489362 (-7474 5935);
PAINT SKYBLUE (-7474 5935);
DISPLAY INVISIBLE (-7474 5935);
FORCEADD OFFPAGE..2
(-600 6000);
FORCEPROP 2 LAST $XR1 80 
J 0
(-321 6000);
DISPLAY 0.638298 (-321 6000);
PAINT MONO (-321 6000);
FORCEPROP 2 LAST $XR0 34 
J 0
(-411 6000);
DISPLAY 0.638298 (-411 6000);
PAINT MONO (-411 6000);
FORCEPROP 2 LAST CDS_LIB standard
J 0
(-600 6000);
DISPLAY INVISIBLE (-600 6000);
FORCEPROP 1 LAST OFFPAGE TRUE
J 0
(-275 5875);
DISPLAY 0.872340 (-275 5875);
PAINT GREEN (-275 5875);
DISPLAY INVISIBLE (-275 5875);
FORCEPROP 1 LAST COMMENT_BODY TRUE
J 0
(-645 5905);
DISPLAY 0.872340 (-645 5905);
PAINT GREEN (-645 5905);
DISPLAY INVISIBLE (-645 5905);
FORCEPROP 2 LAST PATH I2
J 0
(-300 6050);
DISPLAY 0.680851 (-300 6050);
DISPLAY INVISIBLE (-300 6050);
FORCEADD UNIVERSAL_POWER..1
R 2
(-2025 6475);
FORCEPROP 3 LASTPIN (-2025 6425) SIG_NAME P3V3_AUX\g
J 0
(-2015 6435);
DISPLAY 0.659574 (-2015 6435);
PAINT MONO (-2015 6435);
DISPLAY INVISIBLE (-2015 6435);
FORCEPROP 1 LAST HDL_POWER P3V3_AUX
J 1
(-2025 6525);
DISPLAY 0.489362 (-2025 6525);
PAINT GREEN (-2025 6525);
FORCEPROP 2 LAST CDS_LIB pure_quanta_power
J 0
(-2025 6475);
DISPLAY INVISIBLE (-2025 6475);
FORCEPROP 1 LAST PATH I3
J 2
(-2075 6500);
DISPLAY 0.872340 (-2075 6500);
PAINT AQUA (-2075 6500);
DISPLAY INVISIBLE (-2075 6500);
FORCEADD Q_RES..1
(-1675 6000);
FORCEPROP 1 LAST LOCATION R499
J 0
(-1925 6000);
DISPLAY 0.489362 (-1925 6000);
PAINT SKYBLUE (-1925 6000);
FORCEPROP 2 LAST $SEC 1
J 0
(-1725 6200);
DISPLAY 0.680851 (-1725 6200);
PAINT MONO (-1725 6200);
DISPLAY INVISIBLE (-1725 6200);
FORCEPROP 2 LAST CDS_SEC 1
J 0
(-1725 6200);
DISPLAY 0.680851 (-1725 6200);
DISPLAY INVISIBLE (-1725 6200);
FORCEPROP 1 LASTPIN (-1775 6000) $PN 1
J 0
(-1763 6012);
DISPLAY 0.489362 (-1763 6012);
PAINT MONO (-1763 6012);
FORCEPROP 1 LASTPIN (-1575 6000) $PN 2
J 0
(-1613 6012);
DISPLAY 0.489362 (-1613 6012);
PAINT MONO (-1613 6012);
FORCEPROP 1 LAST VALUE 4.7K
J 0
(-1550 6000);
DISPLAY 0.489362 (-1550 6000);
PAINT SKYBLUE (-1550 6000);
FORCEPROP 1 LAST PACK_TYPE 0402LF
J 0
(-1425 5850);
DISPLAY 0.510638 (-1425 5850);
PAINT SKYBLUE (-1425 5850);
DISPLAY INVISIBLE (-1425 5850);
FORCEPROP 1 LAST TOLERANCE 5%
J 0
(-1550 6000);
DISPLAY 0.510638 (-1550 6000);
PAINT SKYBLUE (-1550 6000);
DISPLAY INVISIBLE (-1550 6000);
FORCEPROP 1 LAST MATERIAL CHIP
J 0
(-1575 5975);
DISPLAY 0.489362 (-1575 5975);
PAINT SKYBLUE (-1575 5975);
DISPLAY INVISIBLE (-1575 5975);
FORCEPROP 1 LAST WATTAGE 1/16W
J 2
(-1700 5850);
DISPLAY 0.510638 (-1700 5850);
PAINT SKYBLUE (-1700 5850);
DISPLAY INVISIBLE (-1700 5850);
FORCEPROP 2 LAST CDS_LIB pure_quanta
J 0
(-1675 6000);
DISPLAY INVISIBLE (-1675 6000);
FORCEPROP 1 LAST PATH I4
J 0
(-1725 6150);
DISPLAY 0.978723 (-1725 6150);
PAINT WHITE (-1725 6150);
DISPLAY INVISIBLE (-1725 6150);
FORCEPROP 1 LAST PART_NUMBER CS24702JB10
J 0
(-1725 6100);
DISPLAY 0.510638 (-1725 6100);
PAINT SKYBLUE (-1725 6100);
DISPLAY INVISIBLE (-1725 6100);
FORCEADD UNIVERSAL_GND..1
(-7775 5175);
FORCEPROP 3 LASTPIN (-7775 5225) SIG_NAME GND\g
J 0
(-7765 5235);
DISPLAY 0.659574 (-7765 5235);
PAINT MONO (-7765 5235);
DISPLAY INVISIBLE (-7765 5235);
FORCEPROP 2 LAST CDS_LIB pure_quanta_power
J 0
(-7775 5175);
DISPLAY INVISIBLE (-7775 5175);
FORCEPROP 1 LAST HDL_POWER GND
J 1
(-7750 5100);
DISPLAY 0.872340 (-7750 5100);
PAINT GREEN (-7750 5100);
DISPLAY INVISIBLE (-7750 5100);
FORCEPROP 1 LAST PATH I40
J 0
(-7700 5175);
DISPLAY 0.872340 (-7700 5175);
PAINT AQUA (-7700 5175);
DISPLAY INVISIBLE (-7700 5175);
FORCEADD OFFPAGE..1
(-8575 5625);
FORCEPROP 2 LAST $XR1 34 
J 0
(-8916 5625);
DISPLAY 0.638298 (-8916 5625);
PAINT MONO (-8916 5625);
FORCEPROP 2 LAST $XR0 28 
J 0
(-8826 5625);
DISPLAY 0.638298 (-8826 5625);
PAINT MONO (-8826 5625);
FORCEPROP 2 LAST CDS_LIB standard
J 0
(-8575 5625);
DISPLAY INVISIBLE (-8575 5625);
FORCEPROP 1 LAST OFFPAGE TRUE
J 0
(-8250 5500);
DISPLAY 0.872340 (-8250 5500);
PAINT GREEN (-8250 5500);
DISPLAY INVISIBLE (-8250 5500);
FORCEPROP 1 LAST COMMENT_BODY TRUE
J 0
(-8450 5525);
DISPLAY 0.872340 (-8450 5525);
PAINT GREEN (-8450 5525);
DISPLAY INVISIBLE (-8450 5525);
FORCEPROP 2 LAST PATH I41
J 0
(-8775 5675);
DISPLAY 0.680851 (-8775 5675);
DISPLAY INVISIBLE (-8775 5675);
FORCEADD OFFPAGE..3
R 2
(-8575 5525);
FORCEPROP 2 LAST $XR1 34 
J 0
(-8914 5525);
DISPLAY 0.638298 (-8914 5525);
PAINT MONO (-8914 5525);
FORCEPROP 2 LAST $XR0 28 
J 0
(-8824 5525);
DISPLAY 0.638298 (-8824 5525);
PAINT MONO (-8824 5525);
FORCEPROP 2 LAST CDS_LIB standard
J 0
(-8575 5525);
DISPLAY INVISIBLE (-8575 5525);
FORCEPROP 1 LAST OFFPAGE TRUE
J 2
(-8900 5400);
DISPLAY 0.872340 (-8900 5400);
PAINT GREEN (-8900 5400);
DISPLAY INVISIBLE (-8900 5400);
FORCEPROP 1 LAST COMMENT_BODY TRUE
J 2
(-8525 5425);
DISPLAY 0.872340 (-8525 5425);
PAINT GREEN (-8525 5425);
DISPLAY INVISIBLE (-8525 5425);
FORCEPROP 2 LAST PATH I42
J 0
(-8800 5575);
DISPLAY 0.680851 (-8800 5575);
DISPLAY INVISIBLE (-8800 5575);
FORCEADD UNIVERSAL_POWER..1
R 2
(-7700 6300);
FORCEPROP 3 LASTPIN (-7700 6250) SIG_NAME PVDD18_S5_P0\g
J 0
(-7690 6260);
DISPLAY 0.659574 (-7690 6260);
PAINT MONO (-7690 6260);
DISPLAY INVISIBLE (-7690 6260);
FORCEPROP 1 LAST HDL_POWER PVDD18_S5_P0
J 1
(-7700 6350);
DISPLAY 0.489362 (-7700 6350);
PAINT GREEN (-7700 6350);
FORCEPROP 2 LAST CDS_LIB pure_quanta_power
J 0
(-7700 6300);
DISPLAY INVISIBLE (-7700 6300);
FORCEPROP 1 LAST PATH I43
J 2
(-7750 6325);
DISPLAY 0.872340 (-7750 6325);
PAINT AQUA (-7750 6325);
DISPLAY INVISIBLE (-7750 6325);
FORCEADD Q_CAP..1
(-7875 6025);
FORCEPROP 1 LAST LOCATION C42
J 0
(-7825 6125);
DISPLAY 0.489362 (-7825 6125);
PAINT SKYBLUE (-7825 6125);
FORCEPROP 0 LAST $SEC 1
J 0
(-7825 6175);
DISPLAY 0.680851 (-7825 6175);
PAINT MONO (-7825 6175);
DISPLAY INVISIBLE (-7825 6175);
FORCEPROP 0 LAST CDS_SEC 1
J 0
(-7825 6175);
DISPLAY 1.021277 (-7825 6175);
DISPLAY INVISIBLE (-7825 6175);
FORCEPROP 1 LASTPIN (-7875 6125) $PN 1
J 0
(-7865 6105);
DISPLAY 0.489362 (-7865 6105);
PAINT MONO (-7865 6105);
FORCEPROP 1 LASTPIN (-7875 5925) $PN 2
J 0
(-7865 5905);
DISPLAY 0.489362 (-7865 5905);
PAINT MONO (-7865 5905);
FORCEPROP 1 LAST MATERIAL X7R
J 2
(-7925 5975);
DISPLAY 0.489362 (-7925 5975);
PAINT SKYBLUE (-7925 5975);
FORCEPROP 1 LAST TOLERANCE 10%
J 2
(-7925 6025);
DISPLAY 0.489362 (-7925 6025);
PAINT SKYBLUE (-7925 6025);
FORCEPROP 1 LAST VALUE 0.1UF
J 2
(-7925 6125);
DISPLAY 0.489362 (-7925 6125);
PAINT SKYBLUE (-7925 6125);
FORCEPROP 1 LAST VOLTAGE 25V
J 2
(-7925 6075);
DISPLAY 0.489362 (-7925 6075);
PAINT SKYBLUE (-7925 6075);
FORCEPROP 1 LAST PACK_TYPE 0402
J 2
(-7925 5925);
DISPLAY 0.489362 (-7925 5925);
PAINT SKYBLUE (-7925 5925);
FORCEPROP 2 LAST CDS_LIB pure_quanta
J 0
(-7875 6025);
DISPLAY INVISIBLE (-7875 6025);
FORCEPROP 1 LAST PATH I44
J 0
(-7825 6175);
DISPLAY 0.978723 (-7825 6175);
PAINT WHITE (-7825 6175);
DISPLAY INVISIBLE (-7825 6175);
FORCEPROP 1 LAST PART_NUMBER CH4104K1B00
J 0
(-7825 5875);
DISPLAY 0.489362 (-7825 5875);
PAINT SKYBLUE (-7825 5875);
DISPLAY INVISIBLE (-7825 5875);
FORCEADD UNIVERSAL_GND..1
(-7875 5825);
FORCEPROP 3 LASTPIN (-7875 5875) SIG_NAME GND\g
J 0
(-7865 5885);
DISPLAY 0.659574 (-7865 5885);
PAINT MONO (-7865 5885);
DISPLAY INVISIBLE (-7865 5885);
FORCEPROP 2 LAST CDS_LIB pure_quanta_power
J 0
(-7875 5825);
DISPLAY INVISIBLE (-7875 5825);
FORCEPROP 1 LAST HDL_POWER GND
J 1
(-7850 5750);
DISPLAY 0.872340 (-7850 5750);
PAINT GREEN (-7850 5750);
DISPLAY INVISIBLE (-7850 5750);
FORCEPROP 1 LAST PATH I45
J 0
(-7800 5825);
DISPLAY 0.872340 (-7800 5825);
PAINT AQUA (-7800 5825);
DISPLAY INVISIBLE (-7800 5825);
FORCEADD UNIVERSAL_POWER..1
R 2
(-6625 6350);
FORCEPROP 3 LASTPIN (-6625 6300) SIG_NAME P3V3_AUX\g
J 0
(-6615 6310);
DISPLAY 0.659574 (-6615 6310);
PAINT MONO (-6615 6310);
DISPLAY INVISIBLE (-6615 6310);
FORCEPROP 1 LAST HDL_POWER P3V3_AUX
J 1
(-6625 6400);
DISPLAY 0.489362 (-6625 6400);
PAINT GREEN (-6625 6400);
FORCEPROP 2 LAST CDS_LIB pure_quanta_power
J 0
(-6625 6350);
DISPLAY INVISIBLE (-6625 6350);
FORCEPROP 1 LAST PATH I46
J 2
(-6675 6375);
DISPLAY 0.872340 (-6675 6375);
PAINT AQUA (-6675 6375);
DISPLAY INVISIBLE (-6675 6375);
FORCEADD Q_CAP..1
(-6550 6025);
FORCEPROP 1 LAST LOCATION C43
J 0
(-6500 6175);
DISPLAY 0.489362 (-6500 6175);
PAINT SKYBLUE (-6500 6175);
FORCEPROP 0 LAST $SEC 1
J 0
(-6500 6175);
DISPLAY 0.680851 (-6500 6175);
PAINT MONO (-6500 6175);
DISPLAY INVISIBLE (-6500 6175);
FORCEPROP 0 LAST CDS_SEC 1
J 0
(-6500 6175);
DISPLAY 1.021277 (-6500 6175);
DISPLAY INVISIBLE (-6500 6175);
FORCEPROP 1 LASTPIN (-6550 6125) $PN 1
J 0
(-6540 6105);
DISPLAY 0.489362 (-6540 6105);
PAINT MONO (-6540 6105);
FORCEPROP 1 LASTPIN (-6550 5925) $PN 2
J 0
(-6540 5905);
DISPLAY 0.489362 (-6540 5905);
PAINT MONO (-6540 5905);
FORCEPROP 1 LAST TOLERANCE 10%
J 0
(-6500 6025);
DISPLAY 0.489362 (-6500 6025);
PAINT SKYBLUE (-6500 6025);
FORCEPROP 1 LAST VOLTAGE 25V
J 0
(-6500 6075);
DISPLAY 0.489362 (-6500 6075);
PAINT SKYBLUE (-6500 6075);
FORCEPROP 1 LAST MATERIAL X7R
J 0
(-6500 5975);
DISPLAY 0.489362 (-6500 5975);
PAINT SKYBLUE (-6500 5975);
FORCEPROP 1 LAST VALUE 0.1UF
J 0
(-6500 6125);
DISPLAY 0.489362 (-6500 6125);
PAINT SKYBLUE (-6500 6125);
FORCEPROP 1 LAST PACK_TYPE 0402
J 0
(-6500 5925);
DISPLAY 0.489362 (-6500 5925);
PAINT SKYBLUE (-6500 5925);
FORCEPROP 2 LAST CDS_LIB pure_quanta
J 0
(-6550 6025);
DISPLAY INVISIBLE (-6550 6025);
FORCEPROP 1 LAST PATH I47
J 0
(-6500 6175);
DISPLAY 0.978723 (-6500 6175);
PAINT WHITE (-6500 6175);
DISPLAY INVISIBLE (-6500 6175);
FORCEPROP 1 LAST PART_NUMBER CH4104K1B00
J 0
(-6500 5875);
DISPLAY 0.489362 (-6500 5875);
PAINT SKYBLUE (-6500 5875);
DISPLAY INVISIBLE (-6500 5875);
FORCEADD UNIVERSAL_GND..1
(-6550 5825);
FORCEPROP 3 LASTPIN (-6550 5875) SIG_NAME GND\g
J 0
(-6540 5885);
DISPLAY 0.659574 (-6540 5885);
PAINT MONO (-6540 5885);
DISPLAY INVISIBLE (-6540 5885);
FORCEPROP 2 LAST CDS_LIB pure_quanta_power
J 0
(-6550 5825);
DISPLAY INVISIBLE (-6550 5825);
FORCEPROP 1 LAST HDL_POWER GND
J 1
(-6525 5750);
DISPLAY 0.872340 (-6525 5750);
PAINT GREEN (-6525 5750);
DISPLAY INVISIBLE (-6525 5750);
FORCEPROP 1 LAST PATH I48
J 0
(-6475 5825);
DISPLAY 0.872340 (-6475 5825);
PAINT AQUA (-6475 5825);
DISPLAY INVISIBLE (-6475 5825);
FORCEADD Q_RES..1
(-1675 5925);
FORCEPROP 1 LAST LOCATION R590
J 0
(-1925 5925);
DISPLAY 0.489362 (-1925 5925);
PAINT SKYBLUE (-1925 5925);
FORCEPROP 2 LAST $SEC 1
J 0
(-1725 6125);
DISPLAY 0.680851 (-1725 6125);
PAINT MONO (-1725 6125);
DISPLAY INVISIBLE (-1725 6125);
FORCEPROP 2 LAST CDS_SEC 1
J 0
(-1725 6125);
DISPLAY 0.680851 (-1725 6125);
DISPLAY INVISIBLE (-1725 6125);
FORCEPROP 1 LASTPIN (-1775 5925) $PN 1
J 0
(-1763 5937);
DISPLAY 0.489362 (-1763 5937);
PAINT MONO (-1763 5937);
FORCEPROP 1 LASTPIN (-1575 5925) $PN 2
J 0
(-1613 5937);
DISPLAY 0.489362 (-1613 5937);
PAINT MONO (-1613 5937);
FORCEPROP 1 LAST VALUE 4.7K
J 0
(-1550 5925);
DISPLAY 0.489362 (-1550 5925);
PAINT SKYBLUE (-1550 5925);
FORCEPROP 1 LAST PACK_TYPE 0402LF
J 0
(-1425 5775);
DISPLAY 0.510638 (-1425 5775);
PAINT SKYBLUE (-1425 5775);
DISPLAY INVISIBLE (-1425 5775);
FORCEPROP 1 LAST TOLERANCE 5%
J 0
(-1550 5925);
DISPLAY 0.510638 (-1550 5925);
PAINT SKYBLUE (-1550 5925);
DISPLAY INVISIBLE (-1550 5925);
FORCEPROP 1 LAST MATERIAL CHIP
J 0
(-1575 5900);
DISPLAY 0.489362 (-1575 5900);
PAINT SKYBLUE (-1575 5900);
DISPLAY INVISIBLE (-1575 5900);
FORCEPROP 1 LAST WATTAGE 1/16W
J 2
(-1700 5775);
DISPLAY 0.510638 (-1700 5775);
PAINT SKYBLUE (-1700 5775);
DISPLAY INVISIBLE (-1700 5775);
FORCEPROP 2 LAST CDS_LIB pure_quanta
J 0
(-1675 5925);
DISPLAY INVISIBLE (-1675 5925);
FORCEPROP 1 LAST PATH I5
J 0
(-1725 6075);
DISPLAY 0.978723 (-1725 6075);
PAINT WHITE (-1725 6075);
DISPLAY INVISIBLE (-1725 6075);
FORCEPROP 1 LAST PART_NUMBER CS24702JB10
J 0
(-1725 6025);
DISPLAY 0.510638 (-1725 6025);
PAINT SKYBLUE (-1725 6025);
DISPLAY INVISIBLE (-1725 6025);
FORCEADD OFFPAGE..2
(-5825 5625);
FORCEPROP 2 LAST $XR1 80 
J 0
(-5546 5625);
DISPLAY 0.638298 (-5546 5625);
PAINT MONO (-5546 5625);
FORCEPROP 2 LAST $XR0 34 
J 0
(-5636 5625);
DISPLAY 0.638298 (-5636 5625);
PAINT MONO (-5636 5625);
FORCEPROP 2 LAST CDS_LIB standard
J 0
(-5825 5625);
DISPLAY INVISIBLE (-5825 5625);
FORCEPROP 1 LAST OFFPAGE TRUE
J 0
(-5500 5500);
DISPLAY 0.872340 (-5500 5500);
PAINT GREEN (-5500 5500);
DISPLAY INVISIBLE (-5500 5500);
FORCEPROP 1 LAST COMMENT_BODY TRUE
J 0
(-5870 5530);
DISPLAY 0.872340 (-5870 5530);
PAINT GREEN (-5870 5530);
DISPLAY INVISIBLE (-5870 5530);
FORCEPROP 2 LAST PATH I50
J 0
(-5525 5675);
DISPLAY 0.680851 (-5525 5675);
DISPLAY INVISIBLE (-5525 5675);
FORCEADD OFFPAGE..3
(-5825 5525);
FORCEPROP 2 LAST $XR1 80 
J 0
(-5521 5525);
DISPLAY 0.638298 (-5521 5525);
PAINT MONO (-5521 5525);
FORCEPROP 2 LAST $XR0 34 
J 0
(-5611 5525);
DISPLAY 0.638298 (-5611 5525);
PAINT MONO (-5611 5525);
FORCEPROP 2 LAST CDS_LIB standard
J 0
(-5825 5525);
DISPLAY INVISIBLE (-5825 5525);
FORCEPROP 1 LAST OFFPAGE TRUE
J 0
(-5500 5400);
DISPLAY 0.872340 (-5500 5400);
PAINT GREEN (-5500 5400);
DISPLAY INVISIBLE (-5500 5400);
FORCEPROP 1 LAST COMMENT_BODY TRUE
J 0
(-5875 5425);
DISPLAY 0.872340 (-5875 5425);
PAINT PEACH (-5875 5425);
DISPLAY INVISIBLE (-5875 5425);
FORCEPROP 2 LAST PATH I51
J 0
(-5500 5575);
DISPLAY 0.680851 (-5500 5575);
DISPLAY INVISIBLE (-5500 5575);
FORCEADD OFFPAGE..2
(-3900 2725);
FORCEPROP 2 LAST $XR0 81 
J 0
(-3711 2725);
DISPLAY 0.638298 (-3711 2725);
PAINT MONO (-3711 2725);
FORCEPROP 2 LAST CDS_LIB standard
J 0
(-3900 2725);
DISPLAY INVISIBLE (-3900 2725);
FORCEPROP 1 LAST OFFPAGE TRUE
J 0
(-3575 2600);
DISPLAY 0.872340 (-3575 2600);
PAINT GREEN (-3575 2600);
DISPLAY INVISIBLE (-3575 2600);
FORCEPROP 1 LAST COMMENT_BODY TRUE
J 0
(-3945 2630);
DISPLAY 0.872340 (-3945 2630);
PAINT GREEN (-3945 2630);
DISPLAY INVISIBLE (-3945 2630);
FORCEPROP 2 LAST PATH I52
J 0
(-3725 2800);
DISPLAY 0.680851 (-3725 2800);
DISPLAY INVISIBLE (-3725 2800);
FORCEADD Q_RES..2
(-5400 2975);
FORCEPROP 1 LAST LOCATION R943
J 0
(-5355 3100);
DISPLAY 0.489362 (-5355 3100);
PAINT SKYBLUE (-5355 3100);
FORCEPROP 0 LAST $SEC 1
J 0
(-5350 3150);
DISPLAY 0.680851 (-5350 3150);
PAINT MONO (-5350 3150);
DISPLAY INVISIBLE (-5350 3150);
FORCEPROP 0 LAST CDS_SEC 1
J 0
(-5350 3150);
DISPLAY 0.680851 (-5350 3150);
DISPLAY INVISIBLE (-5350 3150);
FORCEPROP 1 LASTPIN (-5400 3075) $PN 1
J 0
(-5395 3037);
DISPLAY 0.489362 (-5395 3037);
PAINT MONO (-5395 3037);
FORCEPROP 1 LASTPIN (-5400 2875) $PN 2
J 0
(-5395 2885);
DISPLAY 0.489362 (-5395 2885);
PAINT MONO (-5395 2885);
FORCEPROP 1 LAST VALUE 4.7K
J 0
(-5355 3050);
DISPLAY 0.489362 (-5355 3050);
PAINT SKYBLUE (-5355 3050);
FORCEPROP 1 LAST TOLERANCE 5%
J 0
(-5355 3000);
DISPLAY 0.489362 (-5355 3000);
PAINT SKYBLUE (-5355 3000);
FORCEPROP 1 LAST MATERIAL CHIP
J 0
(-5360 2900);
DISPLAY 0.489362 (-5360 2900);
PAINT SKYBLUE (-5360 2900);
FORCEPROP 1 LAST WATTAGE 1/16W
J 0
(-5360 2950);
DISPLAY 0.489362 (-5360 2950);
PAINT SKYBLUE (-5360 2950);
FORCEPROP 1 LAST PACK_TYPE 0402LF
J 0
(-5360 2800);
DISPLAY 0.489362 (-5360 2800);
PAINT SKYBLUE (-5360 2800);
FORCEPROP 2 LAST BOM_COST OCP3.0 
J 0
(-5350 3150);
DISPLAY 0.680851 (-5350 3150);
DISPLAY INVISIBLE (-5350 3150);
FORCEPROP 2 LAST CDS_LIB pure_quanta
J 0
(-5400 2975);
DISPLAY INVISIBLE (-5400 2975);
FORCEPROP 1 LAST PATH I53
J 0
(-5350 3150);
DISPLAY 0.978723 (-5350 3150);
PAINT WHITE (-5350 3150);
DISPLAY INVISIBLE (-5350 3150);
FORCEPROP 1 LAST PART_NUMBER CS24702JB10
J 0
(-5360 2850);
DISPLAY 0.489362 (-5360 2850);
PAINT SKYBLUE (-5360 2850);
DISPLAY INVISIBLE (-5360 2850);
FORCEADD UNIVERSAL_POWER..1
(-5400 3250);
FORCEPROP 3 LASTPIN (-5400 3200) SIG_NAME P1V8_AUX\g
J 0
(-5390 3210);
DISPLAY 0.659574 (-5390 3210);
PAINT MONO (-5390 3210);
DISPLAY INVISIBLE (-5390 3210);
FORCEPROP 1 LAST HDL_POWER P1V8_AUX
J 1
(-5400 3300);
DISPLAY 0.489362 (-5400 3300);
PAINT GREEN (-5400 3300);
FORCEPROP 2 LAST BOM_COST OCP3.0 
J 0
(-5400 3350);
DISPLAY 0.680851 (-5400 3350);
DISPLAY INVISIBLE (-5400 3350);
FORCEPROP 2 LAST CDS_LIB pure_quanta_power
J 0
(-5400 3250);
DISPLAY INVISIBLE (-5400 3250);
FORCEPROP 1 LAST PATH I54
J 0
(-5350 3275);
DISPLAY 0.872340 (-5350 3275);
PAINT AQUA (-5350 3275);
DISPLAY INVISIBLE (-5350 3275);
FORCEADD SN74LVC1G07DBVR..1
(-6350 2725);
FORCEPROP 1 LAST LOCATION U101
J 0
(-6475 2980);
DISPLAY 0.489362 (-6475 2980);
PAINT SKYBLUE (-6475 2980);
FORCEPROP 0 LAST $SEC 1
J 0
(-6475 3125);
DISPLAY 0.680851 (-6475 3125);
PAINT MONO (-6475 3125);
DISPLAY INVISIBLE (-6475 3125);
FORCEPROP 0 LAST CDS_SEC 1
J 0
(-6475 3125);
DISPLAY 0.680851 (-6475 3125);
DISPLAY INVISIBLE (-6475 3125);
FORCEPROP 0 LASTPIN (-6525 2725) $PN 2
J 2
(-6535 2735);
DISPLAY 0.489362 (-6535 2735);
PAINT MONO (-6535 2735);
FORCEPROP 0 LASTPIN (-6525 2625) $PN 3
J 2
(-6535 2635);
DISPLAY 0.489362 (-6535 2635);
PAINT MONO (-6535 2635);
FORCEPROP 0 LASTPIN (-6175 2625) $PN 1
J 0
(-6165 2635);
DISPLAY 0.489362 (-6165 2635);
PAINT MONO (-6165 2635);
FORCEPROP 0 LASTPIN (-6525 2825) $PN 5
J 2
(-6535 2835);
DISPLAY 0.489362 (-6535 2835);
PAINT MONO (-6535 2835);
FORCEPROP 0 LASTPIN (-6175 2725) $PN 4
J 0
(-6165 2735);
DISPLAY 0.489362 (-6165 2735);
PAINT MONO (-6165 2735);
FORCEPROP 1 LAST MATERIAL IC
J 0
(-6475 2885);
DISPLAY 0.489362 (-6475 2885);
PAINT SKYBLUE (-6475 2885);
FORCEPROP 2 LAST PACK_TYPE SMLF
J 0
(-6475 3025);
DISPLAY 0.489362 (-6475 3025);
PAINT SKYBLUE (-6475 3025);
FORCEPROP 2 LAST VALUE SN74LVC1G07DBVR
J 0
(-6475 3075);
DISPLAY 0.489362 (-6475 3075);
PAINT SKYBLUE (-6475 3075);
FORCEPROP 2 LAST CDS_LIB pure_quanta
J 0
(-6350 2725);
DISPLAY INVISIBLE (-6350 2725);
FORCEPROP 1 LAST NEEDS_NO_SIZE TRUE
J 0
(-6350 2725);
DISPLAY 0.468085 (-6350 2725);
PAINT GREEN (-6350 2725);
DISPLAY INVISIBLE (-6350 2725);
FORCEPROP 1 LAST PATH I55
J 0
(-6250 2880);
DISPLAY 0.723404 (-6250 2880);
PAINT GREEN (-6250 2880);
DISPLAY INVISIBLE (-6250 2880);
FORCEPROP 1 LAST PART_NUMBER AL1G0007024
J 0
(-6475 2935);
DISPLAY 0.489362 (-6475 2935);
PAINT SKYBLUE (-6475 2935);
DISPLAY INVISIBLE (-6475 2935);
FORCEADD UNIVERSAL_GND..1
(-6600 2450);
FORCEPROP 3 LASTPIN (-6600 2500) SIG_NAME GND\g
J 0
(-6590 2510);
DISPLAY 0.659574 (-6590 2510);
PAINT MONO (-6590 2510);
DISPLAY INVISIBLE (-6590 2510);
FORCEPROP 2 LAST BOM_COST OCP3.0 
J 0
(-6800 2525);
DISPLAY 0.680851 (-6800 2525);
DISPLAY INVISIBLE (-6800 2525);
FORCEPROP 2 LAST CDS_LIB pure_quanta_power
J 0
(-6600 2450);
DISPLAY INVISIBLE (-6600 2450);
FORCEPROP 1 LAST HDL_POWER GND
J 1
(-6575 2375);
DISPLAY 0.872340 (-6575 2375);
PAINT GREEN (-6575 2375);
DISPLAY INVISIBLE (-6575 2375);
FORCEPROP 1 LAST PATH I56
J 0
(-6525 2450);
DISPLAY 0.872340 (-6525 2450);
PAINT AQUA (-6525 2450);
DISPLAY INVISIBLE (-6525 2450);
FORCEADD UNIVERSAL_GND..1
(-6950 2850);
FORCEPROP 3 LASTPIN (-6950 2900) SIG_NAME GND\g
J 0
(-6940 2910);
DISPLAY 0.659574 (-6940 2910);
PAINT MONO (-6940 2910);
DISPLAY INVISIBLE (-6940 2910);
FORCEPROP 2 LAST BOM_COST OCP3.0 
J 0
(-7150 2925);
DISPLAY 0.680851 (-7150 2925);
DISPLAY INVISIBLE (-7150 2925);
FORCEPROP 2 LAST CDS_LIB pure_quanta_power
J 0
(-6950 2850);
DISPLAY INVISIBLE (-6950 2850);
FORCEPROP 1 LAST HDL_POWER GND
J 1
(-6925 2775);
DISPLAY 0.872340 (-6925 2775);
PAINT GREEN (-6925 2775);
DISPLAY INVISIBLE (-6925 2775);
FORCEPROP 1 LAST PATH I58
J 0
(-6875 2850);
DISPLAY 0.872340 (-6875 2850);
PAINT AQUA (-6875 2850);
DISPLAY INVISIBLE (-6875 2850);
FORCEADD Q_CAP..1
(-6950 3050);
FORCEPROP 1 LAST LOCATION C226
J 0
(-6900 3150);
DISPLAY 0.489362 (-6900 3150);
PAINT SKYBLUE (-6900 3150);
FORCEPROP 0 LAST $SEC 1
J 0
(-6900 3200);
DISPLAY 0.680851 (-6900 3200);
PAINT MONO (-6900 3200);
DISPLAY INVISIBLE (-6900 3200);
FORCEPROP 0 LAST CDS_SEC 1
J 0
(-6900 3200);
DISPLAY 0.680851 (-6900 3200);
DISPLAY INVISIBLE (-6900 3200);
FORCEPROP 1 LASTPIN (-6950 3150) $PN 1
J 0
(-6940 3130);
DISPLAY 0.489362 (-6940 3130);
PAINT MONO (-6940 3130);
FORCEPROP 1 LASTPIN (-6950 2950) $PN 2
J 0
(-6940 2930);
DISPLAY 0.489362 (-6940 2930);
PAINT MONO (-6940 2930);
FORCEPROP 1 LAST PACK_TYPE 0402
J 0
(-6875 2875);
DISPLAY 0.489362 (-6875 2875);
PAINT SKYBLUE (-6875 2875);
FORCEPROP 1 LAST MATERIAL X7R
J 0
(-6875 2975);
DISPLAY 0.489362 (-6875 2975);
PAINT SKYBLUE (-6875 2975);
FORCEPROP 1 LAST TOLERANCE 10%
J 0
(-6875 3025);
DISPLAY 0.489362 (-6875 3025);
PAINT SKYBLUE (-6875 3025);
FORCEPROP 1 LAST VALUE 0.1UF
J 0
(-6875 3125);
DISPLAY 0.489362 (-6875 3125);
PAINT SKYBLUE (-6875 3125);
FORCEPROP 1 LAST VOLTAGE 25V
J 0
(-6875 3075);
DISPLAY 0.489362 (-6875 3075);
PAINT SKYBLUE (-6875 3075);
FORCEPROP 2 LAST CDS_LIB pure_quanta
J 0
(-6950 3050);
DISPLAY INVISIBLE (-6950 3050);
FORCEPROP 2 LAST BOM_COST OCP3.0 
J 0
(-6925 3175);
DISPLAY 0.680851 (-6925 3175);
DISPLAY INVISIBLE (-6925 3175);
FORCEPROP 1 LAST PATH I59
J 0
(-6900 3200);
DISPLAY 0.978723 (-6900 3200);
PAINT WHITE (-6900 3200);
DISPLAY INVISIBLE (-6900 3200);
FORCEPROP 1 LAST PART_NUMBER CH4104K1B00
J 0
(-6875 2925);
DISPLAY 0.489362 (-6875 2925);
PAINT SKYBLUE (-6875 2925);
DISPLAY INVISIBLE (-6875 2925);
FORCEADD Q_RES..2
R 2
(-7075 3050);
FORCEPROP 1 LAST LOCATION R942
J 2
(-7120 3175);
DISPLAY 0.489362 (-7120 3175);
PAINT SKYBLUE (-7120 3175);
FORCEPROP 0 LAST $SEC 1
J 0
(-7100 3225);
DISPLAY 0.680851 (-7100 3225);
PAINT MONO (-7100 3225);
DISPLAY INVISIBLE (-7100 3225);
FORCEPROP 0 LAST CDS_SEC 1
J 0
(-7100 3225);
DISPLAY 0.680851 (-7100 3225);
DISPLAY INVISIBLE (-7100 3225);
FORCEPROP 1 LASTPIN (-7075 3150) $PN 1
J 2
(-7080 3112);
DISPLAY 0.489362 (-7080 3112);
PAINT MONO (-7080 3112);
FORCEPROP 1 LASTPIN (-7075 2950) $PN 2
J 2
(-7080 2960);
DISPLAY 0.489362 (-7080 2960);
PAINT MONO (-7080 2960);
FORCEPROP 1 LAST PACK_TYPE 0402LF
J 2
(-7115 2875);
DISPLAY 0.489362 (-7115 2875);
PAINT SKYBLUE (-7115 2875);
FORCEPROP 1 LAST VALUE 4.7K
J 2
(-7120 3125);
DISPLAY 0.489362 (-7120 3125);
PAINT SKYBLUE (-7120 3125);
FORCEPROP 1 LAST TOLERANCE 5%
J 2
(-7120 3075);
DISPLAY 0.489362 (-7120 3075);
PAINT SKYBLUE (-7120 3075);
FORCEPROP 1 LAST MATERIAL CHIP
J 2
(-7115 2975);
DISPLAY 0.489362 (-7115 2975);
PAINT SKYBLUE (-7115 2975);
FORCEPROP 1 LAST WATTAGE 1/16W
J 2
(-7115 3025);
DISPLAY 0.489362 (-7115 3025);
PAINT SKYBLUE (-7115 3025);
FORCEPROP 2 LAST BOM_COST OCP3.0 
J 2
(-7125 3225);
DISPLAY 0.680851 (-7125 3225);
DISPLAY INVISIBLE (-7125 3225);
FORCEPROP 2 LAST CDS_LIB pure_quanta
J 0
(-7075 3050);
DISPLAY INVISIBLE (-7075 3050);
FORCEPROP 1 LAST PATH I60
J 2
(-7125 3225);
DISPLAY 0.978723 (-7125 3225);
PAINT WHITE (-7125 3225);
DISPLAY INVISIBLE (-7125 3225);
FORCEPROP 1 LAST PART_NUMBER CS24702JB10
J 2
(-7115 2925);
DISPLAY 0.489362 (-7115 2925);
PAINT SKYBLUE (-7115 2925);
DISPLAY INVISIBLE (-7115 2925);
FORCEADD OFFPAGE..1
(-8650 2725);
FORCEPROP 2 LAST $XR1 166 
J 0
(-8991 2725);
DISPLAY 0.638298 (-8991 2725);
PAINT MONO (-8991 2725);
FORCEPROP 2 LAST $XR0 28 
J 0
(-8871 2725);
DISPLAY 0.638298 (-8871 2725);
PAINT MONO (-8871 2725);
FORCEPROP 2 LAST CDS_LIB standard
J 0
(-8650 2725);
DISPLAY INVISIBLE (-8650 2725);
FORCEPROP 1 LAST OFFPAGE TRUE
J 0
(-8325 2600);
DISPLAY 0.872340 (-8325 2600);
PAINT GREEN (-8325 2600);
DISPLAY INVISIBLE (-8325 2600);
FORCEPROP 1 LAST COMMENT_BODY TRUE
J 0
(-8525 2625);
DISPLAY 0.872340 (-8525 2625);
PAINT GREEN (-8525 2625);
DISPLAY INVISIBLE (-8525 2625);
FORCEPROP 2 LAST PATH I61
J 0
(-8600 2800);
DISPLAY 0.680851 (-8600 2800);
DISPLAY INVISIBLE (-8600 2800);
FORCEADD P1V0..1
(-6950 3350);
FORCEPROP 3 LASTPIN (-6950 3300) SIG_NAME PVDD18_S5_P0\g
J 0
(-6940 3310);
DISPLAY 0.659574 (-6940 3310);
PAINT MONO (-6940 3310);
DISPLAY INVISIBLE (-6940 3310);
FORCEPROP 1 LAST HDL_POWER PVDD18_S5_P0
J 1
(-6950 3400);
DISPLAY 0.489362 (-6950 3400);
PAINT GREEN (-6950 3400);
FORCEPROP 2 LAST CDS_LIB pure_quanta_power
J 0
(-6950 3350);
DISPLAY INVISIBLE (-6950 3350);
FORCEPROP 1 LAST PATH I62
J 0
(-6900 3375);
DISPLAY 0.872340 (-6900 3375);
PAINT AQUA (-6900 3375);
DISPLAY INVISIBLE (-6900 3375);
FORCEADD QUANTA_TITLE_BLOCK_C..1
(0 0);
FORCEPROP 0 LAST CDS_CON_LAST_MODIFIED Thu Sep 14 16:11:55 2023
J 0
(-1885 15);
DISPLAY INVISIBLE (-1885 15);
FORCEPROP 1 LAST CUSTOM_TXT_CDS <CON_LAST_MODIFIED>
J 0
(-1885 15);
DISPLAY 0.978723 (-1885 15);
FORCEPROP 2 LAST CUSTOM_TXT_CDS <XR_PAGE_TITLE>
J 0
(-7890 5250);
DISPLAY 0.638298 (-7890 5250);
PAINT PINK (-7890 5250);
DISPLAY INVISIBLE (-7890 5250);
FORCEPROP 1 LAST CUSTOM_TXT_CDS <NAME_2>
J 0
(-3175 50);
FORCEPROP 1 LAST CUSTOM_TXT_CDS <NAME_1>
J 0
(-3175 175);
FORCEPROP 1 LAST CUSTOM_TXT_CDS <Q_NUMBER>
J 0
(-1403 103);
DISPLAY 1.212766 (-1403 103);
FORCEPROP 1 LAST CUSTOM_TXT_CDS <Q_PROJ>
J 0
(-2382 102);
DISPLAY 1.212766 (-2382 102);
FORCEPROP 1 LAST CUSTOM_TXT_CDS <Q_REV>
J 0
(-184 103);
DISPLAY 1.212766 (-184 103);
FORCEPROP 1 LAST CUSTOM_TXT_CDS <CON_PAGE_NUM> OF <CON_TOTAL_PAGES>
J 0
(-446 18);
DISPLAY 0.978723 (-446 18);
FORCEPROP 1 LAST Q_TITLE CPU0 GLUE LOGIC
J 0
(-9275 75);
DISPLAY 2.446809 (-9275 75);
PAINT GREEN (-9275 75);
FORCEPROP 2 LAST PAGE_BORDER TRUE
J 0
(-7890 5250);
DISPLAY 0.638298 (-7890 5250);
PAINT PINK (-7890 5250);
DISPLAY INVISIBLE (-7890 5250);
FORCEPROP 1 LAST CDS_LMAN_SYM_OUTLINE -9475,6775,100,-125
J 0
(0 0);
DISPLAY 0.468085 (0 0);
PAINT GREEN (0 0);
DISPLAY INVISIBLE (0 0);
FORCEPROP 2 LAST CDS_LIB pure_quanta
J 0
(0 0);
DISPLAY INVISIBLE (0 0);
FORCEPROP 2 LAST CDS_XR_PAGE_TITLE CR-34 : @T6G_MB_LIB.T6G(SCH_1):PAGE34
J 0
(-7890 5250);
DISPLAY 0.638298 (-7890 5250);
PAINT PINK (-7890 5250);
DISPLAY INVISIBLE (-7890 5250);
FORCEPROP 1 LAST Q_DEPT BU9
J 1
(-3763 49);
DISPLAY 1.957447 (-3763 49);
PAINT GREEN (-3763 49);
DISPLAY INVISIBLE (-3763 49);
FORCEPROP 1 LAST COMMENT_BODY TRUE
J 0
(12 -13);
DISPLAY 0.978723 (12 -13);
PAINT GREEN (12 -13);
DISPLAY INVISIBLE (12 -13);
WIRE 16 -1 (-4600 2350)(-4600 2300);
WIRE 16 -1 (-7775 5375)(-7625 5375);
WIRE 16 -1 (-7775 5375)(-7775 5225);
WIRE 16 -1 (-7875 5925)(-7875 5875);
WIRE 16 -1 (-6550 5925)(-6550 5875);
WIRE 16 -1 (-5400 3075)(-5400 3200);
WIRE 16 -1 (-6525 2625)(-6600 2625);
WIRE 16 -1 (-6600 2625)(-6600 2500);
WIRE 16 -1 (-6950 2900)(-6950 2950);
WIRE 16 -1 (-2025 4850)(-1725 4850);
WIRE 16 -1 (-2025 4925)(-2025 4850);
WIRE 16 -1 (-2025 4925)(-2025 5350);
WIRE 16 -1 (-2025 4925)(-1725 4925);
WIRE 16 -1 (-1525 4850)(-575 4850);
FORCEPROP 2 LAST SIG_NAME SMB_CPU0_4_SDA
J 0
(-1325 4860);
DISPLAY 0.489362 (-1325 4860);
WIRE 16 -1 (-575 4925)(-1525 4925);
FORCEPROP 2 LAST SIG_NAME SMB_CPU0_4_SCL
J 0
(-1325 4935);
DISPLAY 0.489362 (-1325 4935);
WIRE 16 -1 (-2025 5925)(-1775 5925);
WIRE 16 -1 (-2025 6000)(-2025 5925);
WIRE 16 -1 (-2025 6425)(-2025 6000);
WIRE 16 -1 (-2025 6000)(-1775 6000);
WIRE 16 -1 (-7875 6125)(-7875 6200);
WIRE 16 -1 (-7875 6200)(-7700 6200);
WIRE 16 -1 (-7700 6250)(-7700 6200);
WIRE 16 -1 (-7700 5775)(-7700 6200);
WIRE 16 -1 (-7625 5775)(-7700 5775);
WIRE 16 -1 (-6775 5775)(-6625 5775);
WIRE 16 -1 (-6625 6200)(-6625 5775);
WIRE 16 -1 (-6625 6300)(-6625 6200);
WIRE 16 -1 (-6550 6200)(-6625 6200);
WIRE 16 -1 (-6550 6125)(-6550 6200);
WIRE 16 -1 (-7075 3150)(-7075 3200);
WIRE 16 -1 (-6950 3200)(-7075 3200);
WIRE 16 -1 (-6950 3200)(-6600 3200);
WIRE 16 -1 (-6950 3200)(-6950 3150);
WIRE 16 -1 (-6950 3300)(-6950 3200);
WIRE 16 -1 (-6600 3200)(-6600 2825);
WIRE 16 -1 (-6600 2825)(-6525 2825);
WIRE 16 -1 (-6775 5525)(-5875 5525);
FORCEPROP 2 LAST SIG_NAME SMB_CPU0_4_XLTR_SDA
J 2
(-6210 5535);
DISPLAY 0.489362 (-6210 5535);
WIRE 16 -1 (-6775 5625)(-5875 5625);
FORCEPROP 2 LAST SIG_NAME SMB_CPU0_4_XLTR_SCL
J 2
(-6210 5635);
DISPLAY 0.489362 (-6210 5635);
WIRE 16 -1 (-6775 5375)(-6425 5375);
FORCEPROP 2 LAST SIG_NAME TP_U27_EN
J 0
(-6635 5385);
DISPLAY 0.489362 (-6635 5385);
FORCEPROP 2 LASTPROP $XRERR UNIQUE?
J 0
(-6395 5375);
DISPLAY 0.638298 (-6395 5375);
PAINT MONO (-6395 5375);
DISPLAY INVISIBLE (-6395 5375);
WIRE 16 -1 (-7625 5625)(-8525 5625);
FORCEPROP 2 LAST SIG_NAME SMB_CPU0_4_SCL
J 2
(-7960 5635);
DISPLAY 0.489362 (-7960 5635);
WIRE 16 -1 (-7625 5525)(-8525 5525);
FORCEPROP 2 LAST SIG_NAME SMB_CPU0_4_SDA
J 2
(-7960 5535);
DISPLAY 0.489362 (-7960 5535);
WIRE 16 -1 (-4925 2725)(-4600 2725);
WIRE 16 -1 (-4600 2725)(-3950 2725);
WIRE 16 -1 (-4600 2550)(-4600 2725);
FORCEPROP 2 LAST SIG_NAME FM_BIOS_POST_CMPLT_BUF_N
J 0
(-4610 2735);
DISPLAY 0.489362 (-4610 2735);
WIRE 16 -1 (-1575 5925)(-650 5925);
FORCEPROP 2 LAST SIG_NAME SMB_CPU0_4_XLTR_SDA
J 2
(-985 5935);
DISPLAY 0.489362 (-985 5935);
WIRE 16 -1 (-5400 2725)(-5125 2725);
WIRE 16 -1 (-5400 2725)(-5400 2875);
WIRE 16 -1 (-6175 2725)(-5400 2725);
FORCEPROP 2 LAST SIG_NAME FM_BIOS_POST_CMPLT_BUF_R1_N
J 0
(-6110 2735);
DISPLAY 0.489362 (-6110 2735);
FORCEPROP 2 LASTPROP $XRERR UNIQUE?
J 0
(-6350 2735);
DISPLAY 0.638298 (-6350 2735);
PAINT MONO (-6350 2735);
DISPLAY INVISIBLE (-6350 2735);
WIRE 16 -1 (-1575 6000)(-650 6000);
FORCEPROP 2 LAST SIG_NAME SMB_CPU0_4_XLTR_SCL
J 2
(-985 6010);
DISPLAY 0.489362 (-985 6010);
WIRE 16 -1 (-6525 2725)(-7075 2725);
WIRE 16 -1 (-7075 2725)(-7075 2950);
WIRE 16 -1 (-8600 2725)(-7075 2725);
FORCEPROP 2 LAST SIG_NAME FM_BIOS_POST_CMPLT_N
J 0
(-7710 2735);
DISPLAY 0.489362 (-7710 2735);
DOT 1 (-2025 4925);
DOT 1 (-4600 2725);
DOT 1 (-5400 2725);
DOT 1 (-7075 2725);
DOT 1 (-7700 6200);
DOT 1 (-2025 6000);
DOT 1 (-6950 3200);
DOT 1 (-6625 6200);
FORCENOTE
INTERNAL PU
(-7400 5100) 0;
DISPLAY LEFT (-7400 5100);
DISPLAY 1.021277 (-7400 5100);
QUIT
